(kicad_pcb
	(version 20241229)
	(generator "pcbnew")
	(generator_version "9.0")
	(general
		(thickness 1.599998)
		(legacy_teardrops no)
	)
	(paper "A4")
	(title_block
		(title "Artix - Datacenter Secure Control Module (DC-SCM)")
		(date "2024-11-06")
		(rev "1.1.3")
		(comment 9 "footprints 257-263 of 544")
	)
	(layers
		(0 "F.Cu" signal)
		(4 "In1.Cu" signal)
		(6 "In2.Cu" signal)
		(8 "In3.Cu" signal)
		(10 "In4.Cu" signal)
		(12 "In5.Cu" signal)
		(14 "In6.Cu" signal)
		(2 "B.Cu" signal)
		(9 "F.Adhes" user "F.Adhesive")
		(11 "B.Adhes" user "B.Adhesive")
		(13 "F.Paste" user)
		(15 "B.Paste" user)
		(5 "F.SilkS" user "F.Silkscreen")
		(7 "B.SilkS" user "B.Silkscreen")
		(1 "F.Mask" user)
		(3 "B.Mask" user)
		(17 "Dwgs.User" user "User.Drawings")
		(19 "Cmts.User" user "User.Comments")
		(21 "Eco1.User" user "User.Eco1")
		(23 "Eco2.User" user "User.Eco2")
		(25 "Edge.Cuts" user)
		(27 "Margin" user)
		(31 "F.CrtYd" user "F.Courtyard")
		(29 "B.CrtYd" user "B.Courtyard")
		(35 "F.Fab" user)
		(33 "B.Fab" user)
	)
	(footprint "antmicro-footprints:R_0402_1005Metric"
		(layer "F.Cu")
		(at 127.45 93.1125 180)
		(descr "Resistor SMD 0402")
		(tags "resistor SMD 0402")
		(property "Reference" "R193"
			(at 0.85 -0.254167 0)
			(layer "F.SilkS")
			(effects
				(font
					(size 0.7 0.7)
					(thickness 0.15)
				)
				(justify right bottom)
			)
		)
		(property "Value" "R_22R_0402"
			(at 0 1.4 0)
			(layer "F.Fab")
			(effects
				(font
					(size 0.7 0.7)
					(thickness 0.15)
				)
				(justify right bottom)
			)
		)
		(property "Datasheet" "https://www.bourns.com/docs/product-datasheets/cr.pdf"
			(at 0 0 180)
			(layer "F.Fab")
			(hide yes)
			(effects
				(font
					(size 1.27 1.27)
					(thickness 0.15)
				)
			)
		)
		(property "Description" "SMD Chip Resistor, 22 ohm, ± 1%, 62.5 mW, 0402 [1005 Metric], Thick Film, General Purpose"
			(at 0 0 180)
			(layer "F.Fab")
			(hide yes)
			(effects
				(font
					(size 1.27 1.27)
					(thickness 0.15)
				)
			)
		)
		(property "Author" "Antmicro"
			(at 254.9 186.225 0)
			(layer "F.Fab")
			(hide yes)
			(effects
				(font
					(size 1 1)
					(thickness 0.15)
				)
			)
		)
		(property "License" "Apache-2.0"
			(at 254.9 186.225 0)
			(layer "F.Fab")
			(hide yes)
			(effects
				(font
					(size 1 1)
					(thickness 0.15)
				)
			)
		)
		(property "MPN" "CR0402-FX-22R0GLF"
			(at 254.9 186.225 0)
			(layer "F.Fab")
			(hide yes)
			(effects
				(font
					(size 1 1)
					(thickness 0.15)
				)
			)
		)
		(property "Manufacturer" "Bourns"
			(at 254.9 186.225 0)
			(layer "F.Fab")
			(hide yes)
			(effects
				(font
					(size 1 1)
					(thickness 0.15)
				)
			)
		)
		(property "Tolerance" "1%"
			(at 254.9 186.225 0)
			(layer "F.Fab")
			(hide yes)
			(effects
				(font
					(size 1 1)
					(thickness 0.15)
				)
			)
		)
		(property "Val" "22R"
			(at 254.9 186.225 0)
			(layer "F.Fab")
			(hide yes)
			(effects
				(font
					(size 1 1)
					(thickness 0.15)
				)
			)
		)
		(sheetname "/Interfaces/")
		(sheetfile "interfaces.kicad_sch")
		(attr smd)
		(fp_rect
			(start -0.925 -0.47)
			(end 0.925 0.47)
			(stroke
				(width 0.05)
				(type default)
			)
			(fill no)
			(layer "F.CrtYd")
		)
		(fp_rect
			(start -0.5 -0.25)
			(end 0.5 0.25)
			(stroke
				(width 0.15)
				(type solid)
			)
			(fill no)
			(layer "F.Fab")
		)
		(pad "1" smd roundrect
			(at -0.48 0 180)
			(size 0.59 0.64)
			(layers "F.Cu" "F.Mask" "F.Paste")
			(roundrect_rratio 0.25)
			(net 399 "Net-(U19-ADBUS3)")
			(pintype "passive")
		)
		(pad "2" smd roundrect
			(at 0.48 0 180)
			(size 0.59 0.64)
			(layers "F.Cu" "F.Mask" "F.Paste")
			(roundrect_rratio 0.25)
			(net 16 "JTAG_TMS")
			(pintype "passive")
		)
	)
	(footprint "antmicro-footprints:R_0402_1005Metric"
		(layer "F.Cu")
		(at 127.45 90.845833 180)
		(descr "Resistor SMD 0402")
		(tags "resistor SMD 0402")
		(property "Reference" "R191"
			(at 0.85 -0.254167 0)
			(layer "F.SilkS")
			(effects
				(font
					(size 0.7 0.7)
					(thickness 0.15)
				)
				(justify right bottom)
			)
		)
		(property "Value" "R_22R_0402"
			(at 0 1.4 0)
			(layer "F.Fab")
			(effects
				(font
					(size 0.7 0.7)
					(thickness 0.15)
				)
				(justify right bottom)
			)
		)
		(property "Datasheet" "https://www.bourns.com/docs/product-datasheets/cr.pdf"
			(at 0 0 180)
			(layer "F.Fab")
			(hide yes)
			(effects
				(font
					(size 1.27 1.27)
					(thickness 0.15)
				)
			)
		)
		(property "Description" "SMD Chip Resistor, 22 ohm, ± 1%, 62.5 mW, 0402 [1005 Metric], Thick Film, General Purpose"
			(at 0 0 180)
			(layer "F.Fab")
			(hide yes)
			(effects
				(font
					(size 1.27 1.27)
					(thickness 0.15)
				)
			)
		)
		(property "Author" "Antmicro"
			(at 254.9 181.691666 0)
			(layer "F.Fab")
			(hide yes)
			(effects
				(font
					(size 1 1)
					(thickness 0.15)
				)
			)
		)
		(property "License" "Apache-2.0"
			(at 254.9 181.691666 0)
			(layer "F.Fab")
			(hide yes)
			(effects
				(font
					(size 1 1)
					(thickness 0.15)
				)
			)
		)
		(property "MPN" "CR0402-FX-22R0GLF"
			(at 254.9 181.691666 0)
			(layer "F.Fab")
			(hide yes)
			(effects
				(font
					(size 1 1)
					(thickness 0.15)
				)
			)
		)
		(property "Manufacturer" "Bourns"
			(at 254.9 181.691666 0)
			(layer "F.Fab")
			(hide yes)
			(effects
				(font
					(size 1 1)
					(thickness 0.15)
				)
			)
		)
		(property "Tolerance" "1%"
			(at 254.9 181.691666 0)
			(layer "F.Fab")
			(hide yes)
			(effects
				(font
					(size 1 1)
					(thickness 0.15)
				)
			)
		)
		(property "Val" "22R"
			(at 254.9 181.691666 0)
			(layer "F.Fab")
			(hide yes)
			(effects
				(font
					(size 1 1)
					(thickness 0.15)
				)
			)
		)
		(sheetname "/Interfaces/")
		(sheetfile "interfaces.kicad_sch")
		(attr smd)
		(fp_rect
			(start -0.925 -0.47)
			(end 0.925 0.47)
			(stroke
				(width 0.05)
				(type default)
			)
			(fill no)
			(layer "F.CrtYd")
		)
		(fp_rect
			(start -0.5 -0.25)
			(end 0.5 0.25)
			(stroke
				(width 0.15)
				(type solid)
			)
			(fill no)
			(layer "F.Fab")
		)
		(pad "1" smd roundrect
			(at -0.48 0 180)
			(size 0.59 0.64)
			(layers "F.Cu" "F.Mask" "F.Paste")
			(roundrect_rratio 0.25)
			(net 348 "Net-(U19-ADBUS1)")
			(pintype "passive")
		)
		(pad "2" smd roundrect
			(at 0.48 0 180)
			(size 0.59 0.64)
			(layers "F.Cu" "F.Mask" "F.Paste")
			(roundrect_rratio 0.25)
			(net 13 "JTAG_TDI")
			(pintype "passive")
		)
	)
	(footprint "antmicro-footprints:R_0402_1005Metric"
		(layer "F.Cu")
		(at 130.425 88.7125 90)
		(descr "Resistor SMD 0402")
		(tags "resistor SMD 0402")
		(property "Reference" "R197"
			(at 0.8125 0.375 90)
			(layer "F.SilkS")
			(effects
				(font
					(size 0.7 0.7)
					(thickness 0.15)
				)
				(justify left bottom)
			)
		)
		(property "Value" "R_4k7_0402"
			(at 0 1.4 90)
			(layer "F.Fab")
			(effects
				(font
					(size 0.7 0.7)
					(thickness 0.15)
				)
				(justify left bottom)
			)
		)
		(property "Datasheet" "https://www.bourns.com/docs/product-datasheets/cr.pdf"
			(at 0 0 90)
			(layer "F.Fab")
			(hide yes)
			(effects
				(font
					(size 1.27 1.27)
					(thickness 0.15)
				)
			)
		)
		(property "Description" "SMD Chip Resistor, 4.7 kohm, ± 1%, 62.5 mW, 0402 [1005 Metric], Thick Film, General Purpose"
			(at 0 0 90)
			(layer "F.Fab")
			(hide yes)
			(effects
				(font
					(size 1.27 1.27)
					(thickness 0.15)
				)
			)
		)
		(property "Author" "Antmicro"
			(at 219.1375 -41.7125 0)
			(layer "F.Fab")
			(hide yes)
			(effects
				(font
					(size 1 1)
					(thickness 0.15)
				)
			)
		)
		(property "License" "Apache-2.0"
			(at 219.1375 -41.7125 0)
			(layer "F.Fab")
			(hide yes)
			(effects
				(font
					(size 1 1)
					(thickness 0.15)
				)
			)
		)
		(property "MPN" "CR0402-FX-4701GLF"
			(at 219.1375 -41.7125 0)
			(layer "F.Fab")
			(hide yes)
			(effects
				(font
					(size 1 1)
					(thickness 0.15)
				)
			)
		)
		(property "Manufacturer" "Bourns"
			(at 219.1375 -41.7125 0)
			(layer "F.Fab")
			(hide yes)
			(effects
				(font
					(size 1 1)
					(thickness 0.15)
				)
			)
		)
		(property "Tolerance" "1%"
			(at 219.1375 -41.7125 0)
			(layer "F.Fab")
			(hide yes)
			(effects
				(font
					(size 1 1)
					(thickness 0.15)
				)
			)
		)
		(property "Val" "4k7"
			(at 219.1375 -41.7125 0)
			(layer "F.Fab")
			(hide yes)
			(effects
				(font
					(size 1 1)
					(thickness 0.15)
				)
			)
		)
		(sheetname "/Interfaces/")
		(sheetfile "interfaces.kicad_sch")
		(attr smd)
		(fp_rect
			(start -0.925 -0.47)
			(end 0.925 0.47)
			(stroke
				(width 0.05)
				(type default)
			)
			(fill no)
			(layer "F.CrtYd")
		)
		(fp_rect
			(start -0.5 -0.25)
			(end 0.5 0.25)
			(stroke
				(width 0.15)
				(type solid)
			)
			(fill no)
			(layer "F.Fab")
		)
		(pad "1" smd roundrect
			(at -0.48 0 90)
			(size 0.59 0.64)
			(layers "F.Cu" "F.Mask" "F.Paste")
			(roundrect_rratio 0.25)
			(net 299 "Net-(U19-~{RESET})")
			(pintype "passive")
		)
		(pad "2" smd roundrect
			(at 0.48 0 90)
			(size 0.59 0.64)
			(layers "F.Cu" "F.Mask" "F.Paste")
			(roundrect_rratio 0.25)
			(net 240 "/Interfaces/VBUS")
			(pintype "passive")
		)
	)
	(footprint "antmicro-footprints:R_0402_1005Metric"
		(layer "F.Cu")
		(at 130.885 104.775 180)
		(descr "Resistor SMD 0402")
		(tags "resistor SMD 0402")
		(property "Reference" "R196"
			(at 0.785 -0.425 0)
			(layer "F.SilkS")
			(effects
				(font
					(size 0.7 0.7)
					(thickness 0.15)
				)
				(justify right bottom)
			)
		)
		(property "Value" "R_22R_0402"
			(at 0 1.4 0)
			(layer "F.Fab")
			(effects
				(font
					(size 0.7 0.7)
					(thickness 0.15)
				)
				(justify right bottom)
			)
		)
		(property "Datasheet" "https://www.bourns.com/docs/product-datasheets/cr.pdf"
			(at 0 0 180)
			(layer "F.Fab")
			(hide yes)
			(effects
				(font
					(size 1.27 1.27)
					(thickness 0.15)
				)
			)
		)
		(property "Description" "SMD Chip Resistor, 22 ohm, ± 1%, 62.5 mW, 0402 [1005 Metric], Thick Film, General Purpose"
			(at 0 0 180)
			(layer "F.Fab")
			(hide yes)
			(effects
				(font
					(size 1.27 1.27)
					(thickness 0.15)
				)
			)
		)
		(property "Author" "Antmicro"
			(at 261.77 209.55 0)
			(layer "F.Fab")
			(hide yes)
			(effects
				(font
					(size 1 1)
					(thickness 0.15)
				)
			)
		)
		(property "License" "Apache-2.0"
			(at 261.77 209.55 0)
			(layer "F.Fab")
			(hide yes)
			(effects
				(font
					(size 1 1)
					(thickness 0.15)
				)
			)
		)
		(property "MPN" "CR0402-FX-22R0GLF"
			(at 261.77 209.55 0)
			(layer "F.Fab")
			(hide yes)
			(effects
				(font
					(size 1 1)
					(thickness 0.15)
				)
			)
		)
		(property "Manufacturer" "Bourns"
			(at 261.77 209.55 0)
			(layer "F.Fab")
			(hide yes)
			(effects
				(font
					(size 1 1)
					(thickness 0.15)
				)
			)
		)
		(property "Tolerance" "1%"
			(at 261.77 209.55 0)
			(layer "F.Fab")
			(hide yes)
			(effects
				(font
					(size 1 1)
					(thickness 0.15)
				)
			)
		)
		(property "Val" "22R"
			(at 261.77 209.55 0)
			(layer "F.Fab")
			(hide yes)
			(effects
				(font
					(size 1 1)
					(thickness 0.15)
				)
			)
		)
		(sheetname "/Interfaces/")
		(sheetfile "interfaces.kicad_sch")
		(attr smd)
		(fp_rect
			(start -0.925 -0.47)
			(end 0.925 0.47)
			(stroke
				(width 0.05)
				(type default)
			)
			(fill no)
			(layer "F.CrtYd")
		)
		(fp_rect
			(start -0.5 -0.25)
			(end 0.5 0.25)
			(stroke
				(width 0.15)
				(type solid)
			)
			(fill no)
			(layer "F.Fab")
		)
		(pad "1" smd roundrect
			(at -0.48 0 180)
			(size 0.59 0.64)
			(layers "F.Cu" "F.Mask" "F.Paste")
			(roundrect_rratio 0.25)
			(net 401 "Net-(U19-CDBUS1)")
			(pintype "passive")
		)
		(pad "2" smd roundrect
			(at 0.48 0 180)
			(size 0.59 0.64)
			(layers "F.Cu" "F.Mask" "F.Paste")
			(roundrect_rratio 0.25)
			(net 626 "DBG_UART_TX")
			(pintype "passive")
		)
	)
	(footprint "antmicro-footprints:MP_Pad5.5mm_Drill2.9mm"
		(layer "F.Cu")
		(at 65.6 80.105)
		(descr "mounting hole")
		(property "Reference" "MP1"
			(at -3.58 -2.585 0)
			(layer "F.SilkS")
			(effects
				(font
					(size 0.7 0.7)
					(thickness 0.15)
				)
				(justify left bottom)
			)
		)
		(property "Value" "MP_Pad5.5mm_Drill2.9mm"
			(at 0 3.7 0)
			(layer "F.Fab")
			(effects
				(font
					(size 0.7 0.7)
					(thickness 0.15)
				)
				(justify left bottom)
			)
		)
		(property "Description" "PCB mounting point"
			(at 0 0 0)
			(layer "F.Fab")
			(hide yes)
			(effects
				(font
					(size 1.27 1.27)
					(thickness 0.15)
				)
			)
		)
		(property "Author" "Antmicro"
			(at 0 0 0)
			(layer "F.Fab")
			(hide yes)
			(effects
				(font
					(size 1 1)
					(thickness 0.15)
				)
			)
		)
		(property "License" "Apache-2.0"
			(at 0 0 0)
			(layer "F.Fab")
			(hide yes)
			(effects
				(font
					(size 1 1)
					(thickness 0.15)
				)
			)
		)
		(sheetname "/")
		(sheetfile "artix-dc-scm.kicad_sch")
		(attr exclude_from_pos_files exclude_from_bom)
		(fp_circle
			(center 0 0)
			(end 3 0)
			(stroke
				(width 0.05)
				(type default)
			)
			(fill no)
			(layer "F.CrtYd")
		)
		(pad "1" thru_hole circle
			(at 0 0)
			(size 5.5 5.5)
			(drill 2.9)
			(layers "*.Cu" "*.Mask")
			(remove_unused_layers no)
			(net 690 "unconnected-(MP1-Pad1)")
			(pintype "passive+no_connect")
			(solder_paste_margin_ratio -1)
		)
	)
	(footprint "antmicro-footprints:MP_Pad5.5mm_Drill2.9mm"
		(layer "F.Cu")
		(at 144.6 80.105)
		(descr "mounting hole")
		(property "Reference" "MP2"
			(at 0 -2.9 0)
			(layer "F.SilkS")
			(effects
				(font
					(size 0.7 0.7)
					(thickness 0.15)
				)
				(justify left bottom)
			)
		)
		(property "Value" "MP_Pad5.5mm_Drill2.9mm"
			(at 0 3.7 0)
			(layer "F.Fab")
			(effects
				(font
					(size 0.7 0.7)
					(thickness 0.15)
				)
				(justify left bottom)
			)
		)
		(property "Description" "PCB mounting point"
			(at 0 0 0)
			(layer "F.Fab")
			(hide yes)
			(effects
				(font
					(size 1.27 1.27)
					(thickness 0.15)
				)
			)
		)
		(property "Author" "Antmicro"
			(at 0 0 0)
			(layer "F.Fab")
			(hide yes)
			(effects
				(font
					(size 1 1)
					(thickness 0.15)
				)
			)
		)
		(property "License" "Apache-2.0"
			(at 0 0 0)
			(layer "F.Fab")
			(hide yes)
			(effects
				(font
					(size 1 1)
					(thickness 0.15)
				)
			)
		)
		(sheetname "/")
		(sheetfile "artix-dc-scm.kicad_sch")
		(attr exclude_from_pos_files exclude_from_bom)
		(fp_circle
			(center 0 0)
			(end 3 0)
			(stroke
				(width 0.05)
				(type default)
			)
			(fill no)
			(layer "F.CrtYd")
		)
		(pad "1" thru_hole circle
			(at 0 0)
			(size 5.5 5.5)
			(drill 2.9)
			(layers "*.Cu" "*.Mask")
			(remove_unused_layers no)
			(net 691 "unconnected-(MP2-Pad1)")
			(pintype "passive+no_connect")
			(solder_paste_margin_ratio -1)
		)
	)
	(footprint "antmicro-footprints:R_0402_1005Metric"
		(layer "F.Cu")
		(at 130.875 103.775 180)
		(descr "Resistor SMD 0402")
		(tags "resistor SMD 0402")
		(property "Reference" "R195"
			(at 0.785 -0.425 0)
			(layer "F.SilkS")
			(effects
				(font
					(size 0.7 0.7)
					(thickness 0.15)
				)
				(justify right bottom)
			)
		)
		(property "Value" "R_22R_0402"
			(at 0 1.4 0)
			(layer "F.Fab")
			(effects
				(font
					(size 0.7 0.7)
					(thickness 0.15)
				)
				(justify right bottom)
			)
		)
		(property "Datasheet" "https://www.bourns.com/docs/product-datasheets/cr.pdf"
			(at 0 0 180)
			(layer "F.Fab")
			(hide yes)
			(effects
				(font
					(size 1.27 1.27)
					(thickness 0.15)
				)
			)
		)
		(property "Description" "SMD Chip Resistor, 22 ohm, ± 1%, 62.5 mW, 0402 [1005 Metric], Thick Film, General Purpose"
			(at 0 0 180)
			(layer "F.Fab")
			(hide yes)
			(effects
				(font
					(size 1.27 1.27)
					(thickness 0.15)
				)
			)
		)
		(property "Author" "Antmicro"
			(at 261.75 207.55 0)
			(layer "F.Fab")
			(hide yes)
			(effects
				(font
					(size 1 1)
					(thickness 0.15)
				)
			)
		)
		(property "License" "Apache-2.0"
			(at 261.75 207.55 0)
			(layer "F.Fab")
			(hide yes)
			(effects
				(font
					(size 1 1)
					(thickness 0.15)
				)
			)
		)
		(property "MPN" "CR0402-FX-22R0GLF"
			(at 261.75 207.55 0)
			(layer "F.Fab")
			(hide yes)
			(effects
				(font
					(size 1 1)
					(thickness 0.15)
				)
			)
		)
		(property "Manufacturer" "Bourns"
			(at 261.75 207.55 0)
			(layer "F.Fab")
			(hide yes)
			(effects
				(font
					(size 1 1)
					(thickness 0.15)
				)
			)
		)
		(property "Tolerance" "1%"
			(at 261.75 207.55 0)
			(layer "F.Fab")
			(hide yes)
			(effects
				(font
					(size 1 1)
					(thickness 0.15)
				)
			)
		)
		(property "Val" "22R"
			(at 261.75 207.55 0)
			(layer "F.Fab")
			(hide yes)
			(effects
				(font
					(size 1 1)
					(thickness 0.15)
				)
			)
		)
		(sheetname "/Interfaces/")
		(sheetfile "interfaces.kicad_sch")
		(attr smd)
		(fp_rect
			(start -0.925 -0.47)
			(end 0.925 0.47)
			(stroke
				(width 0.05)
				(type default)
			)
			(fill no)
			(layer "F.CrtYd")
		)
		(fp_rect
			(start -0.5 -0.25)
			(end 0.5 0.25)
			(stroke
				(width 0.15)
				(type solid)
			)
			(fill no)
			(layer "F.Fab")
		)
		(pad "1" smd roundrect
			(at -0.48 0 180)
			(size 0.59 0.64)
			(layers "F.Cu" "F.Mask" "F.Paste")
			(roundrect_rratio 0.25)
			(net 400 "Net-(U19-CDBUS0)")
			(pintype "passive")
		)
		(pad "2" smd roundrect
			(at 0.48 0 180)
			(size 0.59 0.64)
			(layers "F.Cu" "F.Mask" "F.Paste")
			(roundrect_rratio 0.25)
			(net 624 "DBG_UART_RX")
			(pintype "passive")
		)
	)
)
